FILE_TYPE = CONNECTIVITY;
{Allegro Design Entry HDL 16.6-p007 (v16-6-112F) 10/10/2012}
"PAGE_NUMBER" = 241;
0"NC";
1"GND\g";
2"GND\g";
3"GND\g";
4"AGND_P5V_STBY\g";
5"GND\g";
6"GND\g";
7"AGND_P5V_STBY\g";
8"AGND_P5V_STBY\g";
9"GND\g";
10"AGND_P5V_STBY\g";
11"P5V_STBY\g";
12"P12V_STBY\g";
13"P5V_STBY\g";
14"AGND_P5V_STBY\g";
15"GND\g";
16"GND\g";
17"GND\g";
18"GND\g";
19"VR_FET_SW_P5V_STBY_PVIN";
20"VR_P5V_STBY_VSENSE";
21"VR_P5V_STBY_EN";
22"VR_P5V_STBY_VIN";
23"VR_P5V_STBY_PHASE";
24"VR_P5V_STBY_SS";
25"VR_P5V_STBY_RC_COMP";
26"PWRGD_P5V_STBY";
27"VR_P5V_STBY_BOOT";
28"VR_P5V_STBY_VSENSE_R";
29"VR_P5V_STBY_RT";
30"VR_P5V_STBY_COMP";
31"PWRGD_P5V_STBY_R";
32"PWRGD_P12V_HSC_DLY";
%"ST220U10VDM-LGP"
"1","(2850,3825)","0","w_hdl","I100";
;
CDS_SEC"1"
CDS_LOCATION"C8E4"
PACK_SIZE"ESR=25MOHM"
TYPE"TMAX=105C"
RATED"10V"
TOLERANCE"IRP=2400MA"
ATTRIBUTE"220UF"
LOCATION"C8E4"
VALUE"ST220U10VDM-LGP"
PACK_TYPE"SMD-TCG"
SEC"1"
SEC_TYPE"SMD-TCG"
CDS_LMAN_SYM_OUTLINE"-50,25,50,-25"
CDS_LIB"w_hdl"
PART_NUMBER"77.22271.L03";
"2"
$PN"2"5;
"1"
$PN"1"11;
%"SC22U16V5MX-4-GP"
"1","(3400,3825)","0","w_hdl","I103";
;
VALUE"SC22U16V5MX-4-GP"
PACK_SIZE"0805"
RATED"16V"
TYPE"X6S"
ATTRIBUTE"22UF"
TOLERANCE"20%"
LOCATION"C8E7"
CDS_SEC"1"
PACK_TYPE"SMD-BCG5"
SEC"1"
SEC_TYPE"SMD-BCG5"
PART_NUMBER"078.22611.0811"
CDS_LIB"w_hdl"
CDS_LMAN_SYM_OUTLINE"-50,25,50,-25"
CDS_LOCATION"C8E7";
"2"
$PN"2"5;
"1"
$PN"1"11;
%"SC22U16V5MX-4-GP"
"1","(3800,3825)","0","w_hdl","I104";
;
ATTRIBUTE"22UF"
TOLERANCE"20%"
RATED"16V"
TYPE"X6S"
PACK_SIZE"0805"
LOCATION"C8E9"
VALUE"SC22U16V5MX-4-GP"
CDS_LOCATION"C8E9"
CDS_SEC"1"
PACK_TYPE"SMD-BCG5"
SEC"1"
SEC_TYPE"SMD-BCG5"
PART_NUMBER"078.22611.0811"
CDS_LIB"w_hdl"
CDS_LMAN_SYM_OUTLINE"-50,25,50,-25";
"2"
$PN"2"5;
"1"
$PN"1"11;
%"RES"
"2","(1225,4850)","0","mstr_discrete","I11";
;
CDS_SEC"1"
WATTAGE"1/16W"
VALUE"1.00K"
TOLERANCE"1%"
MATERIAL"CHIP"
PACK_TYPE"0402"
LOCATION"R7E12"
PART_NUMBER"G21796-026"
SEC_TYPE"0402"
REUSE_ID"21"
BOM_COST"P5V_STBY_VR"
SEC"1"
ROOM"P5V_STBY_VR"
CDS_LOCATION"R7E12"
CDS_LIB"mstr_discrete";
"A"
$PN"1"13;
"B"
$PN"2"31;
%"CAP"
"2","(1200,3675)","0","mstr_discrete","I12";
;
CDS_SEC"1"
MATERIAL"X7R"
VOLTAGE"25V"
PACK_TYPE"0603LF"
LOCATION"C8E6"
PART_NUMBER"602433-020"
TOLERANCE"10%"
VALUE"0.1UF"
SEC_TYPE"0603LF"
SEC"1"
SPOF"TRUE"
REUSE_ID"27"
BOM_COST"P5V_STBY_VR"
CDS_LIB"mstr_discrete"
CDS_LOCATION"C8E6"
ROOM"P5V_STBY_VR";
"A"
$PN"1"27;
"B"
$PN"2"23;
%"CAP"
"1","(1500,4400)","0","mstr_discrete","I14";
;
CDS_SEC"1"
PACK_TYPE"0402LF"
MATERIAL"X7R"
TOLERANCE"10%"
PART_NUMBER"A36096-046"
VALUE"1000PF"
VOLTAGE"50V"
LOCATION"C7E10"
SEC"1"
REUSE_ID"17"
SEC_TYPE"0402LF"
ROOM"P5V_STBY_VR"
CDS_LOCATION"C7E10"
BOM_COST"P5V_STBY_VR"
CDS_LIB"mstr_discrete";
"A"
$PN"1"31;
"B"
$PN"2"1;
%"GND"
"1","(1500,4150)","0","mstr_symbols","I16";
;
SIZE"1B"
VOLTAGE"0"
CDS_LIB"mstr_symbols"
BODY_TYPE"PLUMBING"
HDL_POWER"GND";
"A\NAC"1;
%"RES"
"2","(-825,2600)","0","mstr_discrete","I18";
;
CDS_SEC"1"
PART_NUMBER"G21796-224"
VALUE"75K"
TOLERANCE"1%"
WATTAGE"1/16W"
MATERIAL"CHIP"
LOCATION"R7E14"
PACK_TYPE"0402"
SEC_TYPE"0402"
SEC"1"
BOM_COST"P5V_STBY_VR"
ROOM"P5V_STBY_VR"
REUSE_ID"8"
CDS_LOCATION"R7E14"
CDS_LIB"mstr_discrete";
"A"
$PN"1"29;
"B"
$PN"2"10;
%"GND"
"1","(675,3125)","0","mstr_symbols","I19";
;
SIZE"1B"
CDS_LIB"mstr_symbols"
VOLTAGE"0"
BODY_TYPE"PLUMBING"
HDL_POWER"GND";
"A\NAC"2;
%"CAP"
"1","(-1400,3850)","0","mstr_discrete","I30";
;
CDS_SEC"1"
MATERIAL"X6S"
PACK_TYPE"0402"
TOLERANCE"10%"
VOLTAGE"16V"
LOCATION"C7E14"
VALUE"1.0UF"
PART_NUMBER"D97712-011"
CDS_LOCATION"C7E14"
CDS_LIB"mstr_discrete"
BOM_COST"P5V_STBY_VR"
SEC"1"
ROOM"P5V_STBY_VR"
SEC_TYPE"0402"
REUSE_ID"1"
FIN"VR_1P2";
"A"
$PN"1"22;
"B"
$PN"2"3;
%"GND"
"1","(-1400,3550)","0","mstr_symbols","I31";
;
SIZE"1B"
CDS_LIB"mstr_symbols"
VOLTAGE"0"
BODY_TYPE"PLUMBING"
HDL_POWER"GND";
"A\NAC"3;
%"GND"
"1","(-2000,2700)","0","mstr_symbols","I32";
;
HDL_POWER"AGND_P5V_STBY"
VOLTAGE"0"
SIZE"1B"
CDS_LIB"mstr_symbols"
BODY_TYPE"PLUMBING";
"A\NAC"4;
%"RES"
"2","(-1400,4200)","0","mstr_discrete","I37";
;
CDS_SEC"1"
VALUE"0.0"
PACK_TYPE"0402"
WATTAGE"1/16W"
TOLERANCE"5%"
LOCATION"R7E17"
PART_NUMBER"G21497-005"
MATERIAL"CHIP"
CDS_LIB"mstr_discrete"
CDS_LOCATION"R7E17"
SEC"1"
BOM_COST"P5V_STBY_VR"
ROOM"P5V_STBY_VR"
SEC_TYPE"0402"
$REUSE_ID"13"
NO_XNET_CONNECTION"1";
"A"
$PN"1"19;
"B"
$PN"2"22;
%"CAP"
"1","(-1750,4275)","0","mstr_discrete","I39";
;
CDS_SEC"1"
PART_NUMBER"D38464-005"
MATERIAL"X6S"
PACK_TYPE"1206LF"
VOLTAGE"16V"
TOLERANCE"10%"
LOCATION"C7E11"
VALUE"22UF"
BOM_COST"P5V_STBY_VR"
SEC_TYPE"1206LF"
SEC"1"
ROOM"P5V_STBY_VR"
CDS_LIB"mstr_discrete"
CDS_LOCATION"C7E11";
"A"
$PN"1"19;
"B"
$PN"2"6;
%"GND"
"1","(3800,3450)","0","mstr_symbols","I4";
;
CDS_LIB"mstr_symbols"
SIZE"1B"
VOLTAGE"0"
BODY_TYPE"PLUMBING"
HDL_POWER"GND";
"A\NAC"5;
%"GND"
"1","(-1750,4050)","0","mstr_symbols","I40";
;
CDS_LIB"mstr_symbols"
VOLTAGE"0"
SIZE"1B"
BODY_TYPE"PLUMBING"
HDL_POWER"GND";
"A\NAC"6;
%"CAP"
"1","(-2000,3075)","2","mstr_discrete","I41";
;
CDS_SEC"1"
LOCATION"C8E13"
VALUE"1000PF"
VOLTAGE"50V"
TOLERANCE"10%"
PACK_TYPE"0402LF"
MATERIAL"EMPTY"
PART_NUMBER"A36096-046"
CDS_LIB"mstr_discrete"
FIN"VR_1P2"
SEC_TYPE"0402LF"
REUSE_ID"1"
BOM_COST"P5V_STBY_VR"
SEC"1"
CDS_LOCATION"C8E13"
ROOM"P5V_STBY_VR";
"A"
$PN"1"32;
"B"
$PN"2"4;
%"RES"
"2","(1750,3425)","0","mstr_discrete","I50";
;
CDS_SEC"1"
WATTAGE"1/16W"
MATERIAL"CHIP"
PACK_TYPE"0402"
LOCATION"R7F1"
VALUE"10.0K"
PART_NUMBER"G21796-016"
TOLERANCE"1%"
BOM_COST"P5V_STBY_VR"
SPOF"TRUE"
SEC"1"
ROOM"P5V_STBY_VR"
REUSE_ID"9"
SEC_TYPE"0402"
CDS_LOCATION"R7F1"
CDS_LIB"mstr_discrete";
"A"
$PN"1"28;
"B"
$PN"2"20;
%"RES"
"2","(1750,2900)","0","mstr_discrete","I51";
;
CDS_SEC"1"
LOCATION"R7E16"
PART_NUMBER"G21796-095"
VALUE"1.37K"
TOLERANCE"1%"
PACK_TYPE"0402"
MATERIAL"CHIP"
WATTAGE"1/16W"
SEC_TYPE"0402"
BOM_COST"P5V_STBY_VR"
SPOF"TRUE"
REUSE_ID"7"
SEC"1"
ROOM"P5V_STBY_VR"
CDS_LOCATION"R7E16"
CDS_LIB"mstr_discrete";
"A"
$PN"1"20;
"B"
$PN"2"7;
%"GND"
"1","(1750,2625)","0","mstr_symbols","I52";
;
HDL_POWER"AGND_P5V_STBY"
SIZE"1B"
VOLTAGE"0"
CDS_LIB"mstr_symbols"
BODY_TYPE"PLUMBING";
"A\NAC"7;
%"CAP"
"2","(200,2575)","0","mstr_discrete","I53";
;
CDS_SEC"1"
LOCATION"C8E16"
VALUE"270PF"
PACK_TYPE"0402LF"
VOLTAGE"50V"
MATERIAL"X7R"
PART_NUMBER"A36096-065"
TOLERANCE"10%"
SEC_TYPE"0402LF"
CDS_LIB"mstr_discrete"
REUSE_ID"4"
BOM_COST"P5V_STBY_VR"
SEC"1"
CDS_LOCATION"C8E16"
ROOM"P5V_STBY_VR";
"A"
$PN"1"30;
"B"
$PN"2"14;
%"RES"
"1","(-200,2200)","0","mstr_discrete","I54";
;
CDS_SEC"1"
TOLERANCE"1%"
PACK_TYPE"0402"
LOCATION"R8E39"
PART_NUMBER"G21796-254"
VALUE"24.9K"
MATERIAL"CHIP"
WATTAGE"1/16W"
BOM_COST"P5V_STBY_VR"
SEC"1"
SEC_TYPE"0402"
REUSE_ID"10"
ROOM"P5V_STBY_VR"
CDS_LIB"mstr_discrete"
CDS_LOCATION"R8E39";
"B"
$PN"2"25;
"A"
$PN"1"30;
%"GND"
"1","(1925,1325)","0","mstr_symbols","I55";
;
HDL_POWER"AGND_P5V_STBY"
VOLTAGE"0"
SIZE"1B"
CDS_LIB"mstr_symbols"
BODY_TYPE"PLUMBING";
"A\NAC"8;
%"CAP"
"2","(575,2200)","0","mstr_discrete","I57";
;
CDS_SEC"1"
LOCATION"C8F1"
VOLTAGE"50V"
PART_NUMBER"A36096-075"
VALUE"2200PF"
TOLERANCE"10%"
MATERIAL"X7R"
PACK_TYPE"0402LF"
ROOM"P5V_STBY_VR"
SEC"1"
BOM_COST"P5V_STBY_VR"
REUSE_ID"5"
SEC_TYPE"0402LF"
CDS_LOCATION"C8F1"
CDS_LIB"mstr_discrete";
"A"
$PN"1"25;
"B"
$PN"2"14;
%"RES"
"1","(1575,1550)","0","mstr_discrete","I58";
;
CDS_SEC"1"
TOLERANCE"5%"
PACK_TYPE"0402"
MATERIAL"CHIP"
LOCATION"R7E13"
PART_NUMBER"G21497-005"
VALUE"0.0"
WATTAGE"1/16W"
CDS_LIB"mstr_discrete"
SPOF"TRUE"
$REUSE_ID"13"
SEC_TYPE"0402"
BOM_COST"P5V_STBY_VR"
SEC"1"
CDS_LOCATION"R7E13"
ROOM"P5V_STBY_VR";
"B"
$PN"2"8;
"A"
$PN"1"9;
%"GND"
"1","(1350,1325)","0","mstr_symbols","I59";
;
SIZE"1B"
CDS_LIB"mstr_symbols"
VOLTAGE"0"
BODY_TYPE"PLUMBING"
HDL_POWER"GND";
"A\NAC"9;
%"CAP"
"1","(-1025,3000)","2","mstr_discrete","I63";
;
CDS_SEC"1"
VOLTAGE"16V"
PART_NUMBER"A36096-073"
PACK_TYPE"0402LF"
TOLERANCE"10%"
LOCATION"C8E15"
MATERIAL"X7R"
VALUE"0.022UF"
CDS_LIB"mstr_discrete"
SEC_TYPE"0402LF"
REUSE_ID"16"
BOM_COST"P5V_STBY_VR"
SEC"1"
CDS_LOCATION"C8E15"
ROOM"P5V_STBY_VR";
"A"
$PN"1"24;
"B"
$PN"2"10;
%"GND"
"1","(-925,2200)","0","mstr_symbols","I64";
;
HDL_POWER"AGND_P5V_STBY"
VOLTAGE"0"
CDS_LIB"mstr_symbols"
SIZE"1B"
BODY_TYPE"PLUMBING";
"A\NAC"10;
%"P5V_STBY"
"1","(3800,4250)","0","mstr_symbols","I69";
;
VOLTAGE"+5"
CDS_LIB"mstr_symbols"
SIZE"1B"
BODY_TYPE"PLUMBING"
HDL_POWER"P5V_STBY";
"G\NAC"11;
%"P12V_STBY"
"1","(-3525,4875)","0","mstr_symbols","I71";
;
CDS_LIB"mstr_symbols"
SIZE"1B"
VOLTAGE"12.0V"
BODY_TYPE"PLUMBING"
HDL_POWER"P12V_STBY";
"G\NAC"12;
%"RES"
"1","(2075,3650)","0","mstr_discrete","I78";
;
CDS_SEC"1"
SPOF"TRUE"
MATERIAL"CHIP"
TOLERANCE"5%"
VALUE"0.0"
PART_NUMBER"G21497-005"
PACK_TYPE"0402"
WATTAGE"1/16W"
LOCATION"R8E37"
CDS_LIB"mstr_discrete"
SEC_TYPE"0402"
BOM_COST"P5V_STBY_VR"
SEC"1"
ROOM"P5V_STBY_VR"
CDS_LOCATION"R8E37";
"B"
$PN"2"11;
"A"
$PN"1"28;
%"FERRITE"
"1","(-3300,4675)","0","mstr_discrete","I82";
;
CDS_SEC"1"
PART_NUMBER"656554-051"
LOCATION"FB7E1"
PACK_TYPE"SM"
MATERIAL"FB"
VALUE"22"
SEC_TYPE"SM"
SEC"1"
CDS_LIB"mstr_discrete"
BOM_COST"P5V_STBY_VR"
ROOM"P5V_STBY_VR"
CDS_LOCATION"FB7E1";
"A"
$PN"1"12;
"B"
$PN"2"19;
%"TPS54821"
"1","(125,3575)","0","mstr_vreg","I83";
;
CDS_SEC"1"
MATERIAL"IC"
LOCATION"EU7E2"
PART_NUMBER"H63269-001"
CDS_LIB"mstr_vreg"
BOM_COST"P5V_STBY_VR"
PACK_TYPE"LCC"
SEC_TYPE"LCC"
SEC"1"
ROOM"P5V_STBY_VR"
CDS_LOCATION"EU7E2";
"BOOT"
$PN"13"27;
"PWRGD"
$PN"14"31;
"VIN"
$PN"6"22;
"EN"
$PN"10"21;
"SS_TR"
$PN"9"24;
"RT_CLK"
$PN"1"29;
"COMP"
$PN"8"30;
"PVIN<1>"
$PN"5"19;
"PVIN<0>"
$PN"4"19;
"GND<1>"
$PN"3"2;
"GND<0>"
$PN"2"2;
"THPAD"
$PN"15"2;
"PH<1>"
$PN"12"23;
"PH<0>"
$PN"11"23;
"VSENSE"
$PN"7"20;
%"P5V_STBY"
"1","(1225,5050)","0","mstr_symbols","I85";
;
VOLTAGE"+5.0V"
CDS_LIB"mstr_symbols"
SIZE"1B"
BODY_TYPE"PLUMBING"
HDL_POWER"P5V_STBY";
"G\NAC"13;
%"GND"
"1","(975,2075)","0","mstr_symbols","I86";
;
HDL_POWER"AGND_P5V_STBY"
CDS_LIB"mstr_symbols"
VOLTAGE"0"
SIZE"1B"
BODY_TYPE"PLUMBING";
"A\NAC"14;
%"RES"
"1","(2250,4625)","0","mstr_discrete","I89";
;
CDS_SEC"1"
MATERIAL"CHIP"
TOLERANCE"1.0%"
VALUE"22.1"
PACK_TYPE"0402"
LOCATION"R7E15"
PART_NUMBER"G21796-250"
WATTAGE"1/16W"
SEC_TYPE"0402"
ROOM"P5V_STBY_VR"
CDS_LIB"mstr_discrete"
SEC"1"
CDS_LOCATION"R7E15";
"B"
$PN"2"26;
"A"
$PN"1"31;
%"RES"
"2","(2550,3875)","0","mstr_discrete","I9";
;
CDS_SEC"1"
LOCATION"R8E18"
VALUE"1.0K"
PACK_TYPE"0402"
MATERIAL"CHIP"
WATTAGE"1/16W"
TOLERANCE"0.1%"
PART_NUMBER"G85996-004"
SEC_TYPE"0402"
REUSE_ID"34"
SEC"1"
BOM_COST"P5V_STBY_VR"
CDS_LOCATION"R8E18"
ROOM"P5V_STBY_VR"
CDS_LIB"mstr_discrete";
"A"
$PN"1"11;
"B"
$PN"2"5;
%"INDUCTOR"
"1","(2150,4050)","0","mstr_discrete","I90";
;
PART_NUMBER"E98761-003"
LOCATION"L8E1"
VALUE"2.2UH"
MATERIAL"IND"
PACK_TYPE"SM"
$SEC"1"
CDS_SEC"1"
CDS_LOCATION"L8E1"
CDS_LIB"mstr_discrete";
"INA\NAC"
$PN"1"23;
"INB\NAC"
$PN"2"11;
%"RES"
"1","(-1625,3475)","0","mstr_discrete","I91";
;
CDS_SEC"1"
LOCATION"R8E33"
MATERIAL"CHIP"
WATTAGE"1/16W"
VALUE"0.0"
PART_NUMBER"G21497-005"
TOLERANCE"5%"
PACK_TYPE"0402"
SEC_TYPE"0402"
SEC"1"
ROOM"PVCCIN_CPU0_VR"
CDS_LIB"mstr_discrete"
CDS_LOCATION"R8E33";
"B"
$PN"2"21;
"A"
$PN"1"32;
%"SC22U16V5MX-4-GP"
"1","(-2400,4325)","0","w_hdl","I92";
;
CDS_SEC"1"
CDS_LOCATION"C7E13"
ATTRIBUTE"22UF"
TOLERANCE"20%"
VALUE"SC22U16V5MX-4-GP"
RATED"16V"
PACK_SIZE"0805"
TYPE"X6S"
LOCATION"C7E13"
PACK_TYPE"SMD-BCG5"
SEC"1"
SEC_TYPE"SMD-BCG5"
PART_NUMBER"078.22611.0811"
CDS_LIB"w_hdl"
CDS_LMAN_SYM_OUTLINE"-50,25,50,-25";
"2"
$PN"2"16;
"1"
$PN"1"19;
%"GND"
"1","(-2100,4075)","0","mstr_symbols","I93";
;
CDS_LIB"mstr_symbols"
BOM_COST"PVPP_KLM_VR"
ROOM"PVPP_KLM_VR"
VOLTAGE"0"
SIZE"1B"
BODY_TYPE"PLUMBING"
HDL_POWER"GND";
"A\NAC"15;
%"GND"
"1","(-2400,4075)","0","mstr_symbols","I94";
;
CDS_LIB"mstr_symbols"
BOM_COST"PVPP_KLM_VR"
ROOM"PVPP_KLM_VR"
VOLTAGE"0"
SIZE"1B"
BODY_TYPE"PLUMBING"
HDL_POWER"GND";
"A\NAC"16;
%"SC22U16V5MX-4-GP"
"1","(-2100,4325)","0","w_hdl","I95";
;
CDS_SEC"1"
CDS_LOCATION"C22W9"
LOCATION"C22W9"
ATTRIBUTE"22UF"
VALUE"SC22U16V5MX-4-GP"
TOLERANCE"20%"
PACK_SIZE"0805"
TYPE"X6S"
RATED"16V"
CDS_LMAN_SYM_OUTLINE"-50,25,50,-25"
CDS_LIB"w_hdl"
PART_NUMBER"078.22611.0811"
SEC_TYPE"SMD-BCG5"
SEC"1"
PACK_TYPE"SMD-BCG5";
"2"
$PN"2"15;
"1"
$PN"1"19;
%"SC22U16V5MX-4-GP"
"1","(-2750,4325)","0","w_hdl","I96";
;
CDS_SEC"1"
CDS_LOCATION"C22W8"
RATED"16V"
VALUE"SC22U16V5MX-4-GP"
LOCATION"C22W8"
ATTRIBUTE"22UF"
TYPE"X6S"
PACK_SIZE"0805"
TOLERANCE"20%"
PACK_TYPE"SMD-BCG5"
SEC"1"
SEC_TYPE"SMD-BCG5"
PART_NUMBER"078.22611.0811"
CDS_LIB"w_hdl"
CDS_LMAN_SYM_OUTLINE"-50,25,50,-25";
"2"
$PN"2"17;
"1"
$PN"1"19;
%"GND"
"1","(-2750,4075)","0","mstr_symbols","I97";
;
SIZE"1B"
VOLTAGE"0"
ROOM"PVPP_KLM_VR"
BOM_COST"PVPP_KLM_VR"
CDS_LIB"mstr_symbols"
BODY_TYPE"PLUMBING"
HDL_POWER"GND";
"A\NAC"17;
%"SC22U16V5MX-4-GP"
"1","(-3050,4325)","0","w_hdl","I98";
;
CDS_SEC"1"
CDS_LOCATION"C7E12"
PACK_SIZE"0805"
TYPE"X6S"
RATED"16V"
TOLERANCE"20%"
ATTRIBUTE"22UF"
LOCATION"C7E12"
VALUE"SC22U16V5MX-4-GP"
CDS_LMAN_SYM_OUTLINE"-50,25,50,-25"
CDS_LIB"w_hdl"
PART_NUMBER"078.22611.0811"
SEC_TYPE"SMD-BCG5"
SEC"1"
PACK_TYPE"SMD-BCG5";
"2"
$PN"2"18;
"1"
$PN"1"19;
%"GND"
"1","(-3050,4075)","0","mstr_symbols","I99";
;
SIZE"1B"
VOLTAGE"0"
ROOM"PVPP_KLM_VR"
BOM_COST"PVPP_KLM_VR"
CDS_LIB"mstr_symbols"
BODY_TYPE"PLUMBING"
HDL_POWER"GND";
"A\NAC"18;
END.
